# SCM (Grand Teton) — schematic netlist excerpt (pin names and nets, part order shuffled) for the footprints in the layout excerpt that follows; sources: Cadence DE-HDL packaged netlist, KiCad conversion of 12092022_DA0F0TMDCD0_F0T_Management_Board_D_brd_V3_OCP.brd

R411  Q_RES  100 1% CHIP  pkg 0402LF  page 26 : A = FRU_E0 ; B = GND
C86  Q_CAP  0.1UF 25V 10% X7R  pkg 0402  page 16 : A = P1V0_AUX ; B = GND

(kicad_pcb
	(version 20260206)
	(generator "pcbnew")
	(generator_version "10.0")
	(general
		(thickness 1.6)
		(legacy_teardrops no)
	)
	(paper "A4")
	(title_block
		(title "12092022_DA0F0TMDCD0_F0T_Management_Board_D_brd_V3_OCP.brd")
		(comment 1 "Grand Teton / footprints 1237-1238 of 1440")
	)
	(layers
		(0 "F.Cu" signal "TOP")
		(4 "In1.Cu" signal "GND")
		(6 "In2.Cu" signal "IN1")
		(8 "In3.Cu" signal "GND1")
		(10 "In4.Cu" signal "IN2")
		(12 "In5.Cu" signal "VCC")
		(14 "In6.Cu" signal "VCC1")
		(16 "In7.Cu" signal "IN3")
		(18 "In8.Cu" signal "GND2")
		(20 "In9.Cu" signal "IN4")
		(22 "In10.Cu" signal "GND3")
		(2 "B.Cu" signal "BOTTOM")
		(9 "F.Adhes" user "F.Adhesive")
		(11 "B.Adhes" user "B.Adhesive")
		(13 "F.Paste" user "Package Geometry/Pastemask Top")
		(15 "B.Paste" user "Package Geometry/Pastemask Bottom")
		(5 "F.SilkS" user "Ref Des/Silkscreen Top")
		(7 "B.SilkS" user "Ref Des/Silkscreen Bottom")
		(1 "F.Mask" user "Board Geometry/Soldermask Top")
		(3 "B.Mask" user "Board Geometry/Soldermask Bottom")
		(17 "Dwgs.User" user "User.Drawings")
		(19 "Cmts.User" user "User.Comments")
		(21 "Eco1.User" user "User.Eco1")
		(23 "Eco2.User" user "User.Eco2")
		(25 "Edge.Cuts" user "Board Geometry/Outline")
		(27 "Margin" user)
		(31 "F.CrtYd" user "Package Geometry/Place Bound Top")
		(29 "B.CrtYd" user "Package Geometry/Place Bound Bottom")
		(35 "F.Fab" user "Ref Des/Assembly Top")
		(33 "B.Fab" user "Ref Des/Assembly Bottom")
	)
	(footprint ""
		(layer "B.Cu")
		(at 59.551316 -49.314354)
		(property "Reference" "C86"
			(at 0 0 0)
			(layer "B.SilkS")
			(hide yes)
			(effects
				(font
					(size 1.27 1.27)
				)
				(justify mirror)
			)
		)
		(property "Value" ""
			(at 0 0 0)
			(layer "B.Fab")
			(effects
				(font
					(size 1.27 1.27)
				)
				(justify mirror)
			)
		)
		(duplicate_pad_numbers_are_jumpers no)
		(fp_line
			(start -0.7874 -0.4064)
			(end -0.7874 0.4064)
			(stroke
				(width 0.1524)
				(type default)
			)
			(layer "B.SilkS")
		)
		(fp_line
			(start -0.7874 0.4064)
			(end 0.7874 0.4064)
			(stroke
				(width 0.1524)
				(type default)
			)
			(layer "B.SilkS")
		)
		(fp_line
			(start 0.7874 -0.4064)
			(end -0.7874 -0.4064)
			(stroke
				(width 0.1524)
				(type default)
			)
			(layer "B.SilkS")
		)
		(fp_line
			(start 0.7874 0.4064)
			(end 0.7874 -0.4064)
			(stroke
				(width 0.1524)
				(type default)
			)
			(layer "B.SilkS")
		)
		(fp_line
			(start -0.67945 -0.3048)
			(end -0.67945 0.3048)
			(stroke
				(width 0.1)
				(type default)
			)
			(layer "B.Fab")
		)
		(fp_line
			(start -0.67945 0.3048)
			(end -0.120396 0.3048)
			(stroke
				(width 0.1)
				(type default)
			)
			(layer "B.Fab")
		)
		(fp_line
			(start -0.12065 -0.3048)
			(end -0.67945 -0.3048)
			(stroke
				(width 0.1)
				(type default)
			)
			(layer "B.Fab")
		)
		(fp_line
			(start -0.12065 -0.2794)
			(end -0.12065 -0.3048)
			(stroke
				(width 0.1)
				(type default)
			)
			(layer "B.Fab")
		)
		(fp_line
			(start -0.120396 0.2794)
			(end 0.12065 0.2794)
			(stroke
				(width 0.1)
				(type default)
			)
			(layer "B.Fab")
		)
		(fp_line
			(start -0.120396 0.3048)
			(end -0.120396 0.2794)
			(stroke
				(width 0.1)
				(type default)
			)
			(layer "B.Fab")
		)
		(fp_line
			(start 0.12065 -0.305054)
			(end 0.12065 -0.2794)
			(stroke
				(width 0.1)
				(type default)
			)
			(layer "B.Fab")
		)
		(fp_line
			(start 0.12065 -0.2794)
			(end -0.12065 -0.2794)
			(stroke
				(width 0.1)
				(type default)
			)
			(layer "B.Fab")
		)
		(fp_line
			(start 0.12065 0.2794)
			(end 0.12065 0.3048)
			(stroke
				(width 0.1)
				(type default)
			)
			(layer "B.Fab")
		)
		(fp_line
			(start 0.12065 0.3048)
			(end 0.67945 0.3048)
			(stroke
				(width 0.1)
				(type default)
			)
			(layer "B.Fab")
		)
		(fp_line
			(start 0.67945 -0.305054)
			(end 0.12065 -0.305054)
			(stroke
				(width 0.1)
				(type default)
			)
			(layer "B.Fab")
		)
		(fp_line
			(start 0.67945 0.3048)
			(end 0.67945 -0.305054)
			(stroke
				(width 0.1)
				(type default)
			)
			(layer "B.Fab")
		)
		(pad "1" smd circle
			(at 0.40005 0 180)
			(size 0 0)
			(layers "B.Cu" "B.Mask" "B.Paste")
			(net "P1V0_AUX")
		)
		(pad "2" smd circle
			(at -0.40005 0 180)
			(size 0 0)
			(layers "B.Cu" "B.Mask" "B.Paste")
			(net "GND")
		)
	)
	(footprint ""
		(layer "B.Cu")
		(at 83.283552 -28.627578 180)
		(property "Reference" "R411"
			(at 0 0 0)
			(layer "B.SilkS")
			(hide yes)
			(effects
				(font
					(size 1.27 1.27)
				)
				(justify mirror)
			)
		)
		(property "Value" ""
			(at 0 0 0)
			(layer "B.Fab")
			(effects
				(font
					(size 1.27 1.27)
				)
				(justify mirror)
			)
		)
		(duplicate_pad_numbers_are_jumpers no)
		(fp_line
			(start 0.7874 0.4064)
			(end 0.7874 -0.4064)
			(stroke
				(width 0.1524)
				(type default)
			)
			(layer "B.SilkS")
		)
		(fp_line
			(start 0.7874 -0.4064)
			(end -0.7874 -0.4064)
			(stroke
				(width 0.1524)
				(type default)
			)
			(layer "B.SilkS")
		)
		(fp_line
			(start -0.7874 0.4064)
			(end 0.7874 0.4064)
			(stroke
				(width 0.1524)
				(type default)
			)
			(layer "B.SilkS")
		)
		(fp_line
			(start -0.7874 -0.4064)
			(end -0.7874 0.4064)
			(stroke
				(width 0.1524)
				(type default)
			)
			(layer "B.SilkS")
		)
		(fp_line
			(start 0.67945 0.3048)
			(end 0.67945 -0.305054)
			(stroke
				(width 0.1)
				(type default)
			)
			(layer "B.Fab")
		)
		(fp_line
			(start 0.67945 -0.305054)
			(end 0.12065 -0.305054)
			(stroke
				(width 0.1)
				(type default)
			)
			(layer "B.Fab")
		)
		(fp_line
			(start 0.12065 0.3048)
			(end 0.67945 0.3048)
			(stroke
				(width 0.1)
				(type default)
			)
			(layer "B.Fab")
		)
		(fp_line
			(start 0.12065 0.2794)
			(end 0.12065 0.3048)
			(stroke
				(width 0.1)
				(type default)
			)
			(layer "B.Fab")
		)
		(fp_line
			(start 0.12065 -0.2794)
			(end -0.12065 -0.2794)
			(stroke
				(width 0.1)
				(type default)
			)
			(layer "B.Fab")
		)
		(fp_line
			(start 0.12065 -0.305054)
			(end 0.12065 -0.2794)
			(stroke
				(width 0.1)
				(type default)
			)
			(layer "B.Fab")
		)
		(fp_line
			(start -0.120396 0.3048)
			(end -0.120396 0.2794)
			(stroke
				(width 0.1)
				(type default)
			)
			(layer "B.Fab")
		)
		(fp_line
			(start -0.120396 0.2794)
			(end 0.12065 0.2794)
			(stroke
				(width 0.1)
				(type default)
			)
			(layer "B.Fab")
		)
		(fp_line
			(start -0.12065 -0.2794)
			(end -0.12065 -0.3048)
			(stroke
				(width 0.1)
				(type default)
			)
			(layer "B.Fab")
		)
		(fp_line
			(start -0.12065 -0.3048)
			(end -0.67945 -0.3048)
			(stroke
				(width 0.1)
				(type default)
			)
			(layer "B.Fab")
		)
		(fp_line
			(start -0.67945 0.3048)
			(end -0.120396 0.3048)
			(stroke
				(width 0.1)
				(type default)
			)
			(layer "B.Fab")
		)
		(fp_line
			(start -0.67945 -0.3048)
			(end -0.67945 0.3048)
			(stroke
				(width 0.1)
				(type default)
			)
			(layer "B.Fab")
		)
		(pad "1" smd circle
			(at 0.40005 0)
			(size 0 0)
			(layers "B.Cu" "B.Mask" "B.Paste")
			(net "FRU_E0")
		)
		(pad "2" smd circle
			(at -0.40005 0)
			(size 0 0)
			(layers "B.Cu" "B.Mask" "B.Paste")
			(net "GND")
		)
	)
)
